FILE_TYPE = CONNECTIVITY;
{Allegro Design Entry HDL 17.2-2016 S081 (4005846) 1/11/2022}
"PAGE_NUMBER" = 40;
0"NC";
1"M_D_CPU1_SA_DQ<31:0>";
2"M_D_CPU1_SB_DQ<31:0>";
3"M_D_CPU1_SA_CB<7:0>";
4"M_D_CPU1_SB_CB<7:0>";
5"M_D_CPU1_SA_DQS_DP<9:0>";
6"M_D_CPU1_SB_DQS_DP<9:0>";
7"M_D_CPU1_SA_CA<6:0>";
8"M_D_CPU1_SB_CA<6:0>";
9"M_D_CPU1_SA_DQS_DN<9:0>";
10"M_D_CPU1_SB_DQS_DN<9:0>";
11"M_D_CPU1_ALERT_N";
12"TP_M_D_CPU1_SA_TEST39D";
13"M_D_CPU1_ALERT_R_N";
14"M_D_CPU1_CLK_DP<0>";
15"M_D_CPU1_CLK_DN<0>";
16"M_D_CPU1_SA_CS_N<0>";
17"M_D_CPU1_SA_CS_N<1>";
18"M_D_CPU1_SA_RSP<0>";
19"M_D_CPU1_SA_PAR";
20"M_D_CPU1_SB_CS_N<0>";
21"M_D_CPU1_SB_CS_N<1>";
22"M_D_CPU1_SB_RSP<0>";
23"M_D_CPU1_SB_PAR";
24"M_D_CPU1_RESET_N";
25"M_D_CPU1_SB_DQS_DP<9>";
26"M_D_CPU1_SB_CA<3>";
27"M_D_CPU1_SB_CA<6>";
28"M_D_CPU1_SA_CA<6>";
29"M_D_CPU1_SB_CA<5>";
30"M_D_CPU1_SA_CA<5>";
31"M_D_CPU1_SB_CA<4>";
32"M_D_CPU1_SA_CA<4>";
33"M_D_CPU1_SB_DQS_DN<9>";
34"M_D_CPU1_SA_CA<3>";
35"M_D_CPU1_SB_CA<2>";
36"M_D_CPU1_SA_CA<2>";
37"M_D_CPU1_SB_CA<1>";
38"M_D_CPU1_SA_CA<1>";
39"M_D_CPU1_SB_CA<0>";
40"M_D_CPU1_SA_CA<0>";
41"M_D_CPU1_SB_DQS_DP<8>";
42"M_D_CPU1_SB_DQS_DP<7>";
43"M_D_CPU1_SB_DQS_DP<6>";
44"M_D_CPU1_SB_DQS_DP<5>";
45"M_D_CPU1_SB_DQS_DP<4>";
46"M_D_CPU1_SB_DQS_DN<8>";
47"M_D_CPU1_SB_DQS_DP<3>";
48"M_D_CPU1_SB_DQS_DN<7>";
49"M_D_CPU1_SB_DQS_DP<2>";
50"M_D_CPU1_SB_DQS_DN<6>";
51"M_D_CPU1_SB_DQS_DP<1>";
52"M_D_CPU1_SB_DQS_DN<5>";
53"M_D_CPU1_SB_DQS_DP<0>";
54"M_D_CPU1_SB_DQS_DN<4>";
55"M_D_CPU1_SA_DQS_DN<9>";
56"M_D_CPU1_SB_DQS_DN<3>";
57"M_D_CPU1_SB_DQS_DN<2>";
58"M_D_CPU1_SB_DQS_DN<1>";
59"M_D_CPU1_SB_DQS_DN<0>";
60"M_D_CPU1_SA_DQS_DP<0>";
61"M_D_CPU1_SA_DQS_DN<4>";
62"M_D_CPU1_SA_DQS_DN<3>";
63"M_D_CPU1_SA_DQS_DN<2>";
64"M_D_CPU1_SA_DQS_DN<1>";
65"M_D_CPU1_SA_DQS_DN<0>";
66"M_D_CPU1_SA_DQS_DP<9>";
67"M_D_CPU1_SA_DQS_DP<8>";
68"M_D_CPU1_SA_DQS_DP<7>";
69"M_D_CPU1_SA_DQS_DP<6>";
70"M_D_CPU1_SA_DQS_DP<5>";
71"M_D_CPU1_SA_DQS_DP<4>";
72"M_D_CPU1_SA_DQS_DN<8>";
73"M_D_CPU1_SA_DQS_DP<3>";
74"M_D_CPU1_SA_DQS_DN<7>";
75"M_D_CPU1_SA_DQS_DP<2>";
76"M_D_CPU1_SA_DQS_DN<6>";
77"M_D_CPU1_SA_DQS_DP<1>";
78"M_D_CPU1_SA_DQS_DN<5>";
79"M_D_CPU1_SB_CB<2>";
80"M_D_CPU1_SB_CB<1>";
81"M_D_CPU1_SB_CB<0>";
82"M_D_CPU1_SB_CB<7>";
83"M_D_CPU1_SB_CB<6>";
84"M_D_CPU1_SB_CB<5>";
85"M_D_CPU1_SB_CB<4>";
86"M_D_CPU1_SB_CB<3>";
87"M_D_CPU1_SB_DQ<22>";
88"M_D_CPU1_SA_CB<7>";
89"M_D_CPU1_SA_CB<6>";
90"M_D_CPU1_SB_DQ<31>";
91"M_D_CPU1_SA_CB<5>";
92"M_D_CPU1_SB_DQ<30>";
93"M_D_CPU1_SA_CB<4>";
94"M_D_CPU1_SA_CB<3>";
95"M_D_CPU1_SA_CB<2>";
96"M_D_CPU1_SA_CB<1>";
97"M_D_CPU1_SA_CB<0>";
98"M_D_CPU1_SB_DQ<29>";
99"M_D_CPU1_SB_DQ<28>";
100"M_D_CPU1_SB_DQ<27>";
101"M_D_CPU1_SB_DQ<26>";
102"M_D_CPU1_SB_DQ<25>";
103"M_D_CPU1_SB_DQ<24>";
104"M_D_CPU1_SB_DQ<23>";
105"M_D_CPU1_SB_DQ<11>";
106"M_D_CPU1_SB_DQ<10>";
107"M_D_CPU1_SB_DQ<21>";
108"M_D_CPU1_SB_DQ<20>";
109"M_D_CPU1_SB_DQ<9>";
110"M_D_CPU1_SB_DQ<19>";
111"M_D_CPU1_SB_DQ<8>";
112"M_D_CPU1_SB_DQ<18>";
113"M_D_CPU1_SB_DQ<7>";
114"M_D_CPU1_SB_DQ<17>";
115"M_D_CPU1_SB_DQ<6>";
116"M_D_CPU1_SB_DQ<16>";
117"M_D_CPU1_SB_DQ<5>";
118"M_D_CPU1_SB_DQ<15>";
119"M_D_CPU1_SB_DQ<4>";
120"M_D_CPU1_SB_DQ<14>";
121"M_D_CPU1_SB_DQ<3>";
122"M_D_CPU1_SB_DQ<13>";
123"M_D_CPU1_SB_DQ<12>";
124"M_D_CPU1_SA_DQ<17>";
125"M_D_CPU1_SA_DQ<28>";
126"M_D_CPU1_SB_DQ<1>";
127"M_D_CPU1_SA_DQ<27>";
128"M_D_CPU1_SB_DQ<0>";
129"M_D_CPU1_SA_DQ<26>";
130"M_D_CPU1_SA_DQ<25>";
131"M_D_CPU1_SA_DQ<24>";
132"M_D_CPU1_SA_DQ<23>";
133"M_D_CPU1_SA_DQ<22>";
134"M_D_CPU1_SA_DQ<21>";
135"M_D_CPU1_SA_DQ<20>";
136"M_D_CPU1_SA_DQ<31>";
137"M_D_CPU1_SA_DQ<30>";
138"M_D_CPU1_SA_DQ<19>";
139"M_D_CPU1_SA_DQ<18>";
140"M_D_CPU1_SA_DQ<29>";
141"M_D_CPU1_SB_DQ<2>";
142"M_D_CPU1_SA_DQ<2>";
143"M_D_CPU1_SA_DQ<1>";
144"M_D_CPU1_SA_DQ<16>";
145"M_D_CPU1_SA_DQ<0>";
146"M_D_CPU1_SA_DQ<15>";
147"M_D_CPU1_SA_DQ<14>";
148"M_D_CPU1_SA_DQ<13>";
149"M_D_CPU1_SA_DQ<12>";
150"M_D_CPU1_SA_DQ<11>";
151"M_D_CPU1_SA_DQ<10>";
152"M_D_CPU1_SA_DQ<9>";
153"M_D_CPU1_SA_DQ<8>";
154"M_D_CPU1_SA_DQ<7>";
155"M_D_CPU1_SA_DQ<6>";
156"M_D_CPU1_SA_DQ<5>";
157"M_D_CPU1_SA_DQ<4>";
158"M_D_CPU1_SA_DQ<3>";
%"GENOA_SP5"
"4","(-4600,3650)","0","pure_quanta","I159";
;
LOCATION"U26"
$SEC"4"
CDS_SEC"4"
PART_TYPE"SMLF"
MATERIAL"IO"
VALUE"SOCKET6096_13568-001"
PART_NUMBER"DGA^6000030"
CDS_LIB"pure_quanta"
CDS_LMAN_SYM_OUTLINE"-650,2525,650,-2525"
NEEDS_NO_SIZE"TRUE";
"TEST39D"
$PN"BF58"12;
"MD1_CLK_L"
$PN"BG60"0;
"MD1_CLK_H"
$PN"BF60"0;
"MD0_CLK_L"
$PN"BD60"15;
"MD0_CLK_H"
$PN"BC60"14;
"MDB_DQS_H9"
$PN"BV60"25;
"MDB_CA3"
$PN"BJ60"26;
"MDB_PAR"
$PN"BL60"23;
"MDA_PAR"
$PN"BC59"19;
"MDA1_RSP_L"
$PN"BP58"0;
"MDA_DATA2"
$PN"F60"142;
"MDA_DATA17"
$PN"V58"124;
"MDA_DATA28"
$PN"AG60"125;
"MDA_DQS_H0"
$PN"G60"60;
"MDA_DQS_L4"
$PN"AM60"61;
"MDB_CHECK2"
$PN"CA60"79;
"MDB_DATA1"
$PN"CC59"126;
"MDB_DATA11"
$PN"CK58"105;
"MDB_DATA22"
$PN"CW60"87;
"MDA0_RSP_L"
$PN"BN59"18;
"MDA_CHECK7"
$PN"AR59"88;
"MDA_DATA1"
$PN"F58"143;
"MDA_DATA16"
$PN"U60"144;
"MDA_DATA27"
$PN"AE59"127;
"MDA_DQS_L3"
$PN"AF60"62;
"MDB_CHECK1"
$PN"CA59"80;
"MDB_DATA0"
$PN"CB60"128;
"MDB_DATA10"
$PN"CJ60"106;
"MDB_DATA21"
$PN"CW59"107;
"MDA_CHECK6"
$PN"AP60"89;
"MDA_DATA0"
$PN"E60"145;
"MDA_DATA15"
$PN"U59"146;
"MDA_DATA26"
$PN"AD60"129;
"MDA_DQS_L2"
$PN"Y60"63;
"MDB1_CS_L1"
$PN"BM60"0;
"MDB_CHECK0"
$PN"BY60"81;
"MDB_DATA20"
$PN"CV60"108;
"MDB_DATA31"
$PN"DF60"90;
"MDA_CHECK5"
$PN"AP58"91;
"MDA_DATA14"
$PN"T60"147;
"MDA_DATA25"
$PN"AD58"130;
"MDA_DQS_L1"
$PN"P60"64;
"MDB0_CS_L1"
$PN"BN60"21;
"MDB1_CS_L0"
$PN"BL59"0;
"MDB_CA6"
$PN"BK60"27;
"MDB_DATA30"
$PN"DE60"92;
"MDB_DQS_H8"
$PN"DD58"41;
"MDA_CA6"
$PN"BB58"28;
"MDA_CHECK4"
$PN"AN60"93;
"MDA_DATA13"
$PN"T58"148;
"MDA_DATA24"
$PN"AC60"131;
"MDA_DQS_L0"
$PN"H60"65;
"MDB0_CS_L0"
$PN"BM58"20;
"MDB_CA5"
$PN"BK58"29;
"MDB_DQS_H7"
$PN"CV58"42;
"MDA_CA5"
$PN"BB60"30;
"MDA_CHECK3"
$PN"AL59"94;
"MDA_DATA12"
$PN"R60"149;
"MDA_DATA23"
$PN"AC59"132;
"MDB_CA4"
$PN"BJ59"31;
"MDB_DQS_H6"
$PN"CM58"43;
"MDA_CA4"
$PN"BA60"32;
"MDA_CHECK2"
$PN"AK60"95;
"MDA_DATA11"
$PN"N59"150;
"MDA_DATA22"
$PN"AB60"133;
"MDB_DQS_H5"
$PN"CF58"44;
"MDB_DQS_L9"
$PN"BW60"33;
"MDA_CA3"
$PN"BA59"34;
"MDA_CHECK1"
$PN"AK58"96;
"MDA_DATA10"
$PN"M60"151;
"MDA_DATA21"
$PN"AB58"134;
"MDB_CA2"
$PN"BH60"35;
"MDB_DQS_H4"
$PN"BY58"45;
"MDB_DQS_L8"
$PN"DC59"46;
"MDA1_CS_L1"
$PN"AV58"0;
"MDA_CA2"
$PN"AY58"36;
"MDA_CHECK0"
$PN"AJ60"97;
"MDA_DATA20"
$PN"AA60"135;
"MDA_DATA31"
$PN"AJ59"136;
"MDA_DQS_H9"
$PN"AN59"66;
"MDB_CA1"
$PN"BH58"37;
"MDB_DQS_H3"
$PN"DB60"47;
"MDB_DQS_L7"
$PN"CU59"48;
"MDA0_CS_L1"
$PN"AW59"17;
"MDA1_CS_L0"
$PN"AU60"0;
"MDA_CA1"
$PN"AY60"38;
"MDA_DATA30"
$PN"AH60"137;
"MDA_DQS_H8"
$PN"AG59"67;
"MDB_CA0"
$PN"BG59"39;
"MDB_DATA9"
$PN"CJ59"109;
"MDB_DATA19"
$PN"CT58"110;
"MDB_DQS_H2"
$PN"CT60"49;
"MDB_DQS_L6"
$PN"CL59"50;
"MDA0_CS_L0"
$PN"AV60"16;
"MDA_CA0"
$PN"AW60"40;
"MDA_DATA9"
$PN"M58"152;
"MDA_DQS_H7"
$PN"AA59"68;
"MDB_DATA8"
$PN"CH60"111;
"MDB_DATA18"
$PN"CR60"112;
"MDB_DATA29"
$PN"DE59"98;
"MDB_DQS_H1"
$PN"CK60"51;
"MDB_DQS_L5"
$PN"CE59"52;
"MDA_DATA8"
$PN"L60"153;
"MDA_DQS_H6"
$PN"R59"69;
"MDB1_RSP_L"
$PN"BR60"0;
"MDB_DATA7"
$PN"CH58"113;
"MDB_DATA17"
$PN"CR59"114;
"MDB_DATA28"
$PN"DD60"99;
"MDB_DQS_H0"
$PN"CD60"53;
"MDB_DQS_L4"
$PN"BW59"54;
"MDA_DATA7"
$PN"L59"154;
"MDA_DQS_H5"
$PN"J59"70;
"MDA_DQS_L9"
$PN"AM58"55;
"MDB0_RSP_L"
$PN"BP60"22;
"MDB_CHECK7"
$PN"BV58"82;
"MDB_DATA6"
$PN"CG60"115;
"MDB_DATA16"
$PN"CP60"116;
"MDB_DATA27"
$PN"DB58"100;
"MDB_DQS_L3"
$PN"DC60"56;
"MDA_DATA6"
$PN"K60"155;
"MDA_DQS_H4"
$PN"AL60"71;
"MDA_DQS_L8"
$PN"AF58"72;
"MDB_CHECK6"
$PN"BU60"83;
"MDB_DATA5"
$PN"CG59"117;
"MDB_DATA15"
$PN"CP58"118;
"MDB_DATA26"
$PN"DA60"101;
"MDB_DQS_L2"
$PN"CU60"57;
"MDA_DATA5"
$PN"K58"156;
"MDA_DQS_H3"
$PN"AE60"73;
"MDA_DQS_L7"
$PN"Y58"74;
"MDB_CHECK5"
$PN"BU59"84;
"MDB_DATA4"
$PN"CF60"119;
"MDB_DATA14"
$PN"CN60"120;
"MDB_DATA25"
$PN"DA59"102;
"MDB_DQS_L1"
$PN"CL60"58;
"MDA_DATA4"
$PN"J60"157;
"MDA_DATA19"
$PN"W59"138;
"MDA_DQS_H2"
$PN"W60"75;
"MDA_DQS_L6"
$PN"P58"76;
"MDB_CHECK4"
$PN"BT60"85;
"MDB_DATA3"
$PN"CD58"121;
"MDB_DATA13"
$PN"CN59"122;
"MDB_DATA24"
$PN"CY60"103;
"MDB_DQS_L0"
$PN"CE60"59;
"MDA_DATA3"
$PN"G59"158;
"MDA_DATA18"
$PN"V60"139;
"MDA_DATA29"
$PN"AH58"140;
"MDA_DQS_H1"
$PN"N60"77;
"MDA_DQS_L5"
$PN"H58"78;
"MDB_CHECK3"
$PN"CB58"86;
"MDB_DATA2"
$PN"CC60"141;
"MDB_DATA12"
$PN"CM60"123;
"MDB_DATA23"
$PN"CY58"104;
"MD_RESET_L"
$PN"AU59"24;
"MD_ALERT_L"
$PN"AT58"13;
%"TAP"
"1","(-3325,5975)","0","mstr_standard","I162";
;
CDS_LIB"mstr_standard"
BODY_TYPE"PLUMBING"
HDL_TAP"TRUE";
"B \NAC \NWC"1;
"S \NAC"
BN"1"143;
%"TAP"
"1","(-3325,5925)","0","mstr_standard","I163";
;
CDS_LIB"mstr_standard"
BODY_TYPE"PLUMBING"
HDL_TAP"TRUE";
"B \NAC \NWC"1;
"S \NAC"
BN"2"142;
%"TAP"
"1","(-3325,6025)","0","mstr_standard","I164";
;
CDS_LIB"mstr_standard"
BODY_TYPE"PLUMBING"
HDL_TAP"TRUE";
"B \NAC \NWC"1;
"S \NAC"
BN"0"145;
%"TAP"
"1","(-3325,5825)","0","mstr_standard","I165";
;
CDS_LIB"mstr_standard"
BODY_TYPE"PLUMBING"
HDL_TAP"TRUE";
"B \NAC \NWC"1;
"S \NAC"
BN"4"157;
%"TAP"
"1","(-3325,5875)","0","mstr_standard","I166";
;
CDS_LIB"mstr_standard"
BODY_TYPE"PLUMBING"
HDL_TAP"TRUE";
"B \NAC \NWC"1;
"S \NAC"
BN"3"158;
%"TAP"
"1","(-3325,5775)","0","mstr_standard","I167";
;
CDS_LIB"mstr_standard"
BODY_TYPE"PLUMBING"
HDL_TAP"TRUE";
"B \NAC \NWC"1;
"S \NAC"
BN"5"156;
%"TAP"
"1","(-3325,5725)","0","mstr_standard","I168";
;
CDS_LIB"mstr_standard"
BODY_TYPE"PLUMBING"
HDL_TAP"TRUE";
"B \NAC \NWC"1;
"S \NAC"
BN"6"155;
%"TAP"
"1","(-3325,5675)","0","mstr_standard","I169";
;
CDS_LIB"mstr_standard"
BODY_TYPE"PLUMBING"
HDL_TAP"TRUE";
"B \NAC \NWC"1;
"S \NAC"
BN"7"154;
%"TAP"
"1","(-3325,5425)","0","mstr_standard","I170";
;
CDS_LIB"mstr_standard"
BODY_TYPE"PLUMBING"
HDL_TAP"TRUE";
"B \NAC \NWC"1;
"S \NAC"
BN"11"150;
%"TAP"
"1","(-3325,5475)","0","mstr_standard","I171";
;
CDS_LIB"mstr_standard"
BODY_TYPE"PLUMBING"
HDL_TAP"TRUE";
"B \NAC \NWC"1;
"S \NAC"
BN"10"151;
%"TAP"
"1","(-3325,5525)","0","mstr_standard","I172";
;
CDS_LIB"mstr_standard"
BODY_TYPE"PLUMBING"
HDL_TAP"TRUE";
"B \NAC \NWC"1;
"S \NAC"
BN"9"152;
%"TAP"
"1","(-3325,5575)","0","mstr_standard","I173";
;
CDS_LIB"mstr_standard"
BODY_TYPE"PLUMBING"
HDL_TAP"TRUE";
"B \NAC \NWC"1;
"S \NAC"
BN"8"153;
%"TAP"
"1","(-3325,5125)","0","mstr_standard","I174";
;
CDS_LIB"mstr_standard"
BODY_TYPE"PLUMBING"
HDL_TAP"TRUE";
"B \NAC \NWC"1;
"S \NAC"
BN"16"144;
%"TAP"
"1","(-3325,5225)","0","mstr_standard","I175";
;
CDS_LIB"mstr_standard"
BODY_TYPE"PLUMBING"
HDL_TAP"TRUE";
"B \NAC \NWC"1;
"S \NAC"
BN"15"146;
%"TAP"
"1","(-3325,5275)","0","mstr_standard","I176";
;
CDS_LIB"mstr_standard"
BODY_TYPE"PLUMBING"
HDL_TAP"TRUE";
"B \NAC \NWC"1;
"S \NAC"
BN"14"147;
%"TAP"
"1","(-3325,5375)","0","mstr_standard","I177";
;
CDS_LIB"mstr_standard"
BODY_TYPE"PLUMBING"
HDL_TAP"TRUE";
"B \NAC \NWC"1;
"S \NAC"
BN"12"149;
%"TAP"
"1","(-3325,5325)","0","mstr_standard","I178";
;
CDS_LIB"mstr_standard"
BODY_TYPE"PLUMBING"
HDL_TAP"TRUE";
"B \NAC \NWC"1;
"S \NAC"
BN"13"148;
%"TAP"
"1","(-3325,4925)","0","mstr_standard","I179";
;
CDS_LIB"mstr_standard"
BODY_TYPE"PLUMBING"
HDL_TAP"TRUE";
"B \NAC \NWC"1;
"S \NAC"
BN"20"135;
%"TAP"
"1","(-3325,4875)","0","mstr_standard","I180";
;
CDS_LIB"mstr_standard"
BODY_TYPE"PLUMBING"
HDL_TAP"TRUE";
"B \NAC \NWC"1;
"S \NAC"
BN"21"134;
%"TAP"
"1","(-3325,4975)","0","mstr_standard","I181";
;
CDS_LIB"mstr_standard"
BODY_TYPE"PLUMBING"
HDL_TAP"TRUE";
"B \NAC \NWC"1;
"S \NAC"
BN"19"138;
%"TAP"
"1","(-3325,5025)","0","mstr_standard","I182";
;
CDS_LIB"mstr_standard"
BODY_TYPE"PLUMBING"
HDL_TAP"TRUE";
"B \NAC \NWC"1;
"S \NAC"
BN"18"139;
%"TAP"
"1","(-3325,5075)","0","mstr_standard","I183";
;
CDS_LIB"mstr_standard"
BODY_TYPE"PLUMBING"
HDL_TAP"TRUE";
"B \NAC \NWC"1;
"S \NAC"
BN"17"124;
%"TAP"
"1","(-3325,4825)","0","mstr_standard","I184";
;
CDS_LIB"mstr_standard"
BODY_TYPE"PLUMBING"
HDL_TAP"TRUE";
"B \NAC \NWC"1;
"S \NAC"
BN"22"133;
%"TAP"
"1","(-3325,4775)","0","mstr_standard","I185";
;
CDS_LIB"mstr_standard"
BODY_TYPE"PLUMBING"
HDL_TAP"TRUE";
"B \NAC \NWC"1;
"S \NAC"
BN"23"132;
%"TAP"
"1","(-3325,4675)","0","mstr_standard","I186";
;
CDS_LIB"mstr_standard"
BODY_TYPE"PLUMBING"
HDL_TAP"TRUE";
"B \NAC \NWC"1;
"S \NAC"
BN"24"131;
%"TAP"
"1","(-3325,4625)","0","mstr_standard","I187";
;
CDS_LIB"mstr_standard"
BODY_TYPE"PLUMBING"
HDL_TAP"TRUE";
"B \NAC \NWC"1;
"S \NAC"
BN"25"130;
%"TAP"
"1","(-3325,4425)","0","mstr_standard","I188";
;
CDS_LIB"mstr_standard"
BODY_TYPE"PLUMBING"
HDL_TAP"TRUE";
"B \NAC \NWC"1;
"S \NAC"
BN"29"140;
%"TAP"
"1","(-3325,4375)","0","mstr_standard","I189";
;
CDS_LIB"mstr_standard"
BODY_TYPE"PLUMBING"
HDL_TAP"TRUE";
"B \NAC \NWC"1;
"S \NAC"
BN"30"137;
%"TAP"
"1","(-3325,4475)","0","mstr_standard","I190";
;
CDS_LIB"mstr_standard"
BODY_TYPE"PLUMBING"
HDL_TAP"TRUE";
"B \NAC \NWC"1;
"S \NAC"
BN"28"125;
%"TAP"
"1","(-3325,4575)","0","mstr_standard","I191";
;
CDS_LIB"mstr_standard"
BODY_TYPE"PLUMBING"
HDL_TAP"TRUE";
"B \NAC \NWC"1;
"S \NAC"
BN"26"129;
%"TAP"
"1","(-3325,4525)","0","mstr_standard","I192";
;
CDS_LIB"mstr_standard"
BODY_TYPE"PLUMBING"
HDL_TAP"TRUE";
"B \NAC \NWC"1;
"S \NAC"
BN"27"127;
%"TAP"
"1","(-3325,4175)","0","mstr_standard","I193";
;
CDS_LIB"mstr_standard"
BODY_TYPE"PLUMBING"
HDL_TAP"TRUE";
"B \NAC \NWC"2;
"S \NAC"
BN"1"126;
%"TAP"
"1","(-3325,4325)","0","mstr_standard","I194";
;
CDS_LIB"mstr_standard"
BODY_TYPE"PLUMBING"
HDL_TAP"TRUE";
"B \NAC \NWC"1;
"S \NAC"
BN"31"136;
%"TAP"
"1","(-3325,4125)","0","mstr_standard","I195";
;
CDS_LIB"mstr_standard"
BODY_TYPE"PLUMBING"
HDL_TAP"TRUE";
"B \NAC \NWC"2;
"S \NAC"
BN"2"141;
%"TAP"
"1","(-3325,4225)","0","mstr_standard","I196";
;
CDS_LIB"mstr_standard"
BODY_TYPE"PLUMBING"
HDL_TAP"TRUE";
"B \NAC \NWC"2;
"S \NAC"
BN"0"128;
%"TAP"
"1","(-3325,4025)","0","mstr_standard","I198";
;
CDS_LIB"mstr_standard"
BODY_TYPE"PLUMBING"
HDL_TAP"TRUE";
"B \NAC \NWC"2;
"S \NAC"
BN"4"119;
%"TAP"
"1","(-3325,4075)","0","mstr_standard","I199";
;
CDS_LIB"mstr_standard"
BODY_TYPE"PLUMBING"
HDL_TAP"TRUE";
"B \NAC \NWC"2;
"S \NAC"
BN"3"121;
%"TAP"
"1","(-3325,3975)","0","mstr_standard","I200";
;
CDS_LIB"mstr_standard"
BODY_TYPE"PLUMBING"
HDL_TAP"TRUE";
"B \NAC \NWC"2;
"S \NAC"
BN"5"117;
%"TAP"
"1","(-3325,3925)","0","mstr_standard","I201";
;
CDS_LIB"mstr_standard"
BODY_TYPE"PLUMBING"
HDL_TAP"TRUE";
"B \NAC \NWC"2;
"S \NAC"
BN"6"115;
%"TAP"
"1","(-3325,3875)","0","mstr_standard","I202";
;
CDS_LIB"mstr_standard"
BODY_TYPE"PLUMBING"
HDL_TAP"TRUE";
"B \NAC \NWC"2;
"S \NAC"
BN"7"113;
%"TAP"
"1","(-3325,3625)","0","mstr_standard","I203";
;
CDS_LIB"mstr_standard"
BODY_TYPE"PLUMBING"
HDL_TAP"TRUE";
"B \NAC \NWC"2;
"S \NAC"
BN"11"105;
%"TAP"
"1","(-3325,3675)","0","mstr_standard","I204";
;
CDS_LIB"mstr_standard"
BODY_TYPE"PLUMBING"
HDL_TAP"TRUE";
"B \NAC \NWC"2;
"S \NAC"
BN"10"106;
%"TAP"
"1","(-3325,3775)","0","mstr_standard","I205";
;
CDS_LIB"mstr_standard"
BODY_TYPE"PLUMBING"
HDL_TAP"TRUE";
"B \NAC \NWC"2;
"S \NAC"
BN"8"111;
%"TAP"
"1","(-3325,3725)","0","mstr_standard","I206";
;
CDS_LIB"mstr_standard"
BODY_TYPE"PLUMBING"
HDL_TAP"TRUE";
"B \NAC \NWC"2;
"S \NAC"
BN"9"109;
%"TAP"
"1","(-3325,3425)","0","mstr_standard","I207";
;
CDS_LIB"mstr_standard"
BODY_TYPE"PLUMBING"
HDL_TAP"TRUE";
"B \NAC \NWC"2;
"S \NAC"
BN"15"118;
%"TAP"
"1","(-3325,3475)","0","mstr_standard","I208";
;
CDS_LIB"mstr_standard"
BODY_TYPE"PLUMBING"
HDL_TAP"TRUE";
"B \NAC \NWC"2;
"S \NAC"
BN"14"120;
%"TAP"
"1","(-3325,3575)","0","mstr_standard","I209";
;
CDS_LIB"mstr_standard"
BODY_TYPE"PLUMBING"
HDL_TAP"TRUE";
"B \NAC \NWC"2;
"S \NAC"
BN"12"123;
%"TAP"
"1","(-3325,3525)","0","mstr_standard","I210";
;
CDS_LIB"mstr_standard"
BODY_TYPE"PLUMBING"
HDL_TAP"TRUE";
"B \NAC \NWC"2;
"S \NAC"
BN"13"122;
%"TAP"
"1","(-3325,3325)","0","mstr_standard","I211";
;
CDS_LIB"mstr_standard"
BODY_TYPE"PLUMBING"
HDL_TAP"TRUE";
"B \NAC \NWC"2;
"S \NAC"
BN"16"116;
%"TAP"
"1","(-3325,3275)","0","mstr_standard","I212";
;
CDS_LIB"mstr_standard"
BODY_TYPE"PLUMBING"
HDL_TAP"TRUE";
"B \NAC \NWC"2;
"S \NAC"
BN"17"114;
%"TAP"
"1","(-3325,3225)","0","mstr_standard","I213";
;
CDS_LIB"mstr_standard"
BODY_TYPE"PLUMBING"
HDL_TAP"TRUE";
"B \NAC \NWC"2;
"S \NAC"
BN"18"112;
%"TAP"
"1","(-3325,3075)","0","mstr_standard","I214";
;
CDS_LIB"mstr_standard"
BODY_TYPE"PLUMBING"
HDL_TAP"TRUE";
"B \NAC \NWC"2;
"S \NAC"
BN"21"107;
%"TAP"
"1","(-3325,3175)","0","mstr_standard","I215";
;
CDS_LIB"mstr_standard"
BODY_TYPE"PLUMBING"
HDL_TAP"TRUE";
"B \NAC \NWC"2;
"S \NAC"
BN"19"110;
%"TAP"
"1","(-3325,3125)","0","mstr_standard","I216";
;
CDS_LIB"mstr_standard"
BODY_TYPE"PLUMBING"
HDL_TAP"TRUE";
"B \NAC \NWC"2;
"S \NAC"
BN"20"108;
%"TAP"
"1","(-3325,2875)","0","mstr_standard","I217";
;
CDS_LIB"mstr_standard"
BODY_TYPE"PLUMBING"
HDL_TAP"TRUE";
"B \NAC \NWC"2;
"S \NAC"
BN"24"103;
%"TAP"
"1","(-3325,2975)","0","mstr_standard","I218";
;
CDS_LIB"mstr_standard"
BODY_TYPE"PLUMBING"
HDL_TAP"TRUE";
"B \NAC \NWC"2;
"S \NAC"
BN"23"104;
%"TAP"
"1","(-3325,3025)","0","mstr_standard","I219";
;
CDS_LIB"mstr_standard"
BODY_TYPE"PLUMBING"
HDL_TAP"TRUE";
"B \NAC \NWC"2;
"S \NAC"
BN"22"87;
%"TAP"
"1","(-3325,2825)","0","mstr_standard","I220";
;
CDS_LIB"mstr_standard"
BODY_TYPE"PLUMBING"
HDL_TAP"TRUE";
"B \NAC \NWC"2;
"S \NAC"
BN"25"102;
%"TAP"
"1","(-3325,2625)","0","mstr_standard","I221";
;
CDS_LIB"mstr_standard"
BODY_TYPE"PLUMBING"
HDL_TAP"TRUE";
"B \NAC \NWC"2;
"S \NAC"
BN"29"98;
%"TAP"
"1","(-3325,2575)","0","mstr_standard","I222";
;
CDS_LIB"mstr_standard"
BODY_TYPE"PLUMBING"
HDL_TAP"TRUE";
"B \NAC \NWC"2;
"S \NAC"
BN"30"92;
%"TAP"
"1","(-3325,2675)","0","mstr_standard","I223";
;
CDS_LIB"mstr_standard"
BODY_TYPE"PLUMBING"
HDL_TAP"TRUE";
"B \NAC \NWC"2;
"S \NAC"
BN"28"99;
%"TAP"
"1","(-3325,2775)","0","mstr_standard","I224";
;
CDS_LIB"mstr_standard"
BODY_TYPE"PLUMBING"
HDL_TAP"TRUE";
"B \NAC \NWC"2;
"S \NAC"
BN"26"101;
%"TAP"
"1","(-3325,2725)","0","mstr_standard","I225";
;
CDS_LIB"mstr_standard"
BODY_TYPE"PLUMBING"
HDL_TAP"TRUE";
"B \NAC \NWC"2;
"S \NAC"
BN"27"100;
%"TAP"
"1","(-3325,2525)","0","mstr_standard","I226";
;
CDS_LIB"mstr_standard"
BODY_TYPE"PLUMBING"
HDL_TAP"TRUE";
"B \NAC \NWC"2;
"S \NAC"
BN"31"90;
%"TAP"
"1","(-3325,2425)","0","mstr_standard","I227";
;
CDS_LIB"mstr_standard"
BODY_TYPE"PLUMBING"
HDL_TAP"TRUE";
"B \NAC \NWC"3;
"S \NAC"
BN"0"97;
%"TAP"
"1","(-3325,2325)","0","mstr_standard","I228";
;
CDS_LIB"mstr_standard"
BODY_TYPE"PLUMBING"
HDL_TAP"TRUE";
"B \NAC \NWC"3;
"S \NAC"
BN"2"95;
%"TAP"
"1","(-3325,2375)","0","mstr_standard","I229";
;
CDS_LIB"mstr_standard"
BODY_TYPE"PLUMBING"
HDL_TAP"TRUE";
"B \NAC \NWC"3;
"S \NAC"
BN"1"96;
%"TAP"
"1","(-3325,2275)","0","mstr_standard","I230";
;
CDS_LIB"mstr_standard"
BODY_TYPE"PLUMBING"
HDL_TAP"TRUE";
"B \NAC \NWC"3;
"S \NAC"
BN"3"94;
%"TAP"
"1","(-3325,2225)","0","mstr_standard","I231";
;
CDS_LIB"mstr_standard"
BODY_TYPE"PLUMBING"
HDL_TAP"TRUE";
"B \NAC \NWC"3;
"S \NAC"
BN"4"93;
%"TAP"
"1","(-3325,2175)","0","mstr_standard","I232";
;
CDS_LIB"mstr_standard"
BODY_TYPE"PLUMBING"
HDL_TAP"TRUE";
"B \NAC \NWC"3;
"S \NAC"
BN"5"91;
%"TAP"
"1","(-3325,2125)","0","mstr_standard","I233";
;
CDS_LIB"mstr_standard"
BODY_TYPE"PLUMBING"
HDL_TAP"TRUE";
"B \NAC \NWC"3;
"S \NAC"
BN"6"89;
%"TAP"
"1","(-3325,2075)","0","mstr_standard","I234";
;
CDS_LIB"mstr_standard"
BODY_TYPE"PLUMBING"
HDL_TAP"TRUE";
"B \NAC \NWC"3;
"S \NAC"
BN"7"88;
%"TAP"
"1","(-3325,1925)","0","mstr_standard","I236";
;
CDS_LIB"mstr_standard"
BODY_TYPE"PLUMBING"
HDL_TAP"TRUE";
"B \NAC \NWC"4;
"S \NAC"
BN"1"80;
%"TAP"
"1","(-3325,1975)","0","mstr_standard","I237";
;
CDS_LIB"mstr_standard"
BODY_TYPE"PLUMBING"
HDL_TAP"TRUE";
"B \NAC \NWC"4;
"S \NAC"
BN"0"81;
%"TAP"
"1","(-3325,1825)","0","mstr_standard","I238";
;
CDS_LIB"mstr_standard"
BODY_TYPE"PLUMBING"
HDL_TAP"TRUE";
"B \NAC \NWC"4;
"S \NAC"
BN"3"86;
%"TAP"
"1","(-3325,1875)","0","mstr_standard","I239";
;
CDS_LIB"mstr_standard"
BODY_TYPE"PLUMBING"
HDL_TAP"TRUE";
"B \NAC \NWC"4;
"S \NAC"
BN"2"79;
%"TAP"
"1","(-3325,1625)","0","mstr_standard","I240";
;
CDS_LIB"mstr_standard"
BODY_TYPE"PLUMBING"
HDL_TAP"TRUE";
"B \NAC \NWC"4;
"S \NAC"
BN"7"82;
%"TAP"
"1","(-3325,1675)","0","mstr_standard","I241";
;
CDS_LIB"mstr_standard"
BODY_TYPE"PLUMBING"
HDL_TAP"TRUE";
"B \NAC \NWC"4;
"S \NAC"
BN"6"83;
%"TAP"
"1","(-3325,1775)","0","mstr_standard","I242";
;
CDS_LIB"mstr_standard"
BODY_TYPE"PLUMBING"
HDL_TAP"TRUE";
"B \NAC \NWC"4;
"S \NAC"
BN"4"85;
%"TAP"
"1","(-3325,1725)","0","mstr_standard","I243";
;
CDS_LIB"mstr_standard"
BODY_TYPE"PLUMBING"
HDL_TAP"TRUE";
"B \NAC \NWC"4;
"S \NAC"
BN"5"84;
%"TAP"
"1","(-5750,6025)","2","mstr_standard","I244";
;
CDS_LIB"mstr_standard"
BODY_TYPE"PLUMBING"
HDL_TAP"TRUE";
"B \NAC \NWC"5;
"S \NAC"
BN"0"60;
%"TAP"
"1","(-5750,5925)","2","mstr_standard","I245";
;
CDS_LIB"mstr_standard"
BODY_TYPE"PLUMBING"
HDL_TAP"TRUE";
"B \NAC \NWC"5;
"S \NAC"
BN"1"77;
%"TAP"
"1","(-5750,5825)","2","mstr_standard","I246";
;
CDS_LIB"mstr_standard"
BODY_TYPE"PLUMBING"
HDL_TAP"TRUE";
"B \NAC \NWC"5;
"S \NAC"
BN"2"75;
%"TAP"
"1","(-5750,5725)","2","mstr_standard","I247";
;
CDS_LIB"mstr_standard"
BODY_TYPE"PLUMBING"
HDL_TAP"TRUE";
"B \NAC \NWC"5;
"S \NAC"
BN"3"73;
%"TAP"
"1","(-5950,5975)","2","mstr_standard","I248";
;
CDS_LIB"mstr_standard"
BODY_TYPE"PLUMBING"
HDL_TAP"TRUE";
"B \NAC \NWC"9;
"S \NAC"
BN"0"65;
%"TAP"
"1","(-5950,5875)","2","mstr_standard","I249";
;
CDS_LIB"mstr_standard"
BODY_TYPE"PLUMBING"
HDL_TAP"TRUE";
"B \NAC \NWC"9;
"S \NAC"
BN"1"64;
%"TAP"
"1","(-5950,5775)","2","mstr_standard","I250";
;
CDS_LIB"mstr_standard"
BODY_TYPE"PLUMBING"
HDL_TAP"TRUE";
"B \NAC \NWC"9;
"S \NAC"
BN"2"63;
%"TAP"
"1","(-5950,5675)","2","mstr_standard","I251";
;
CDS_LIB"mstr_standard"
BODY_TYPE"PLUMBING"
HDL_TAP"TRUE";
"B \NAC \NWC"9;
"S \NAC"
BN"3"62;
%"TAP"
"1","(-5750,5625)","2","mstr_standard","I252";
;
CDS_LIB"mstr_standard"
BODY_TYPE"PLUMBING"
HDL_TAP"TRUE";
"B \NAC \NWC"5;
"S \NAC"
BN"4"71;
%"TAP"
"1","(-5750,5525)","2","mstr_standard","I253";
;
CDS_LIB"mstr_standard"
BODY_TYPE"PLUMBING"
HDL_TAP"TRUE";
"B \NAC \NWC"5;
"S \NAC"
BN"5"70;
%"TAP"
"1","(-5750,5425)","2","mstr_standard","I254";
;
CDS_LIB"mstr_standard"
BODY_TYPE"PLUMBING"
HDL_TAP"TRUE";
"B \NAC \NWC"5;
"S \NAC"
BN"6"69;
%"TAP"
"1","(-5750,5325)","2","mstr_standard","I255";
;
CDS_LIB"mstr_standard"
BODY_TYPE"PLUMBING"
HDL_TAP"TRUE";
"B \NAC \NWC"5;
"S \NAC"
BN"7"68;
%"TAP"
"1","(-5750,5225)","2","mstr_standard","I256";
;
CDS_LIB"mstr_standard"
BODY_TYPE"PLUMBING"
HDL_TAP"TRUE";
"B \NAC \NWC"5;
"S \NAC"
BN"8"67;
%"TAP"
"1","(-5750,5125)","2","mstr_standard","I257";
;
CDS_LIB"mstr_standard"
BODY_TYPE"PLUMBING"
HDL_TAP"TRUE";
"B \NAC \NWC"5;
"S \NAC"
BN"9"66;
%"TAP"
"1","(-5950,5575)","2","mstr_standard","I258";
;
CDS_LIB"mstr_standard"
BODY_TYPE"PLUMBING"
HDL_TAP"TRUE";
"B \NAC \NWC"9;
"S \NAC"
BN"4"61;
%"TAP"
"1","(-5950,5475)","2","mstr_standard","I259";
;
CDS_LIB"mstr_standard"
BODY_TYPE"PLUMBING"
HDL_TAP"TRUE";
"B \NAC \NWC"9;
"S \NAC"
BN"5"78;
%"TAP"
"1","(-5950,5375)","2","mstr_standard","I260";
;
CDS_LIB"mstr_standard"
BODY_TYPE"PLUMBING"
HDL_TAP"TRUE";
"B \NAC \NWC"9;
"S \NAC"
BN"6"76;
%"TAP"
"1","(-5950,5275)","2","mstr_standard","I261";
;
CDS_LIB"mstr_standard"
BODY_TYPE"PLUMBING"
HDL_TAP"TRUE";
"B \NAC \NWC"9;
"S \NAC"
BN"7"74;
%"TAP"
"1","(-5950,5175)","2","mstr_standard","I262";
;
CDS_LIB"mstr_standard"
BODY_TYPE"PLUMBING"
HDL_TAP"TRUE";
"B \NAC \NWC"9;
"S \NAC"
BN"8"72;
%"TAP"
"1","(-5750,4975)","2","mstr_standard","I263";
;
CDS_LIB"mstr_standard"
BODY_TYPE"PLUMBING"
HDL_TAP"TRUE";
"B \NAC \NWC"6;
"S \NAC"
BN"0"53;
%"TAP"
"1","(-5750,4875)","2","mstr_standard","I264";
;
CDS_LIB"mstr_standard"
BODY_TYPE"PLUMBING"
HDL_TAP"TRUE";
"B \NAC \NWC"6;
"S \NAC"
BN"1"51;
%"TAP"
"1","(-5750,4775)","2","mstr_standard","I265";
;
CDS_LIB"mstr_standard"
BODY_TYPE"PLUMBING"
HDL_TAP"TRUE";
"B \NAC \NWC"6;
"S \NAC"
BN"2"49;
%"TAP"
"1","(-5750,4675)","2","mstr_standard","I266";
;
CDS_LIB"mstr_standard"
BODY_TYPE"PLUMBING"
HDL_TAP"TRUE";
"B \NAC \NWC"6;
"S \NAC"
BN"3"47;
%"TAP"
"1","(-5950,5075)","2","mstr_standard","I267";
;
CDS_LIB"mstr_standard"
BODY_TYPE"PLUMBING"
HDL_TAP"TRUE";
"B \NAC \NWC"9;
"S \NAC"
BN"9"55;
%"TAP"
"1","(-5950,4925)","2","mstr_standard","I268";
;
CDS_LIB"mstr_standard"
BODY_TYPE"PLUMBING"
HDL_TAP"TRUE";
"B \NAC \NWC"10;
"S \NAC"
BN"0"59;
%"TAP"
"1","(-5950,4825)","2","mstr_standard","I269";
;
CDS_LIB"mstr_standard"
BODY_TYPE"PLUMBING"
HDL_TAP"TRUE";
"B \NAC \NWC"10;
"S \NAC"
BN"1"58;
%"TAP"
"1","(-5950,4725)","2","mstr_standard","I270";
;
CDS_LIB"mstr_standard"
BODY_TYPE"PLUMBING"
HDL_TAP"TRUE";
"B \NAC \NWC"10;
"S \NAC"
BN"2"57;
%"TAP"
"1","(-5950,4625)","2","mstr_standard","I271";
;
CDS_LIB"mstr_standard"
BODY_TYPE"PLUMBING"
HDL_TAP"TRUE";
"B \NAC \NWC"10;
"S \NAC"
BN"3"56;
%"TAP"
"1","(-5750,4575)","2","mstr_standard","I272";
;
CDS_LIB"mstr_standard"
BODY_TYPE"PLUMBING"
HDL_TAP"TRUE";
"B \NAC \NWC"6;
"S \NAC"
BN"4"45;
%"TAP"
"1","(-5750,4475)","2","mstr_standard","I273";
;
CDS_LIB"mstr_standard"
BODY_TYPE"PLUMBING"
HDL_TAP"TRUE";
"B \NAC \NWC"6;
"S \NAC"
BN"5"44;
%"TAP"
"1","(-5750,4375)","2","mstr_standard","I274";
;
CDS_LIB"mstr_standard"
BODY_TYPE"PLUMBING"
HDL_TAP"TRUE";
"B \NAC \NWC"6;
"S \NAC"
BN"6"43;
%"TAP"
"1","(-5750,4275)","2","mstr_standard","I275";
;
CDS_LIB"mstr_standard"
BODY_TYPE"PLUMBING"
HDL_TAP"TRUE";
"B \NAC \NWC"6;
"S \NAC"
BN"7"42;
%"TAP"
"1","(-5750,4175)","2","mstr_standard","I276";
;
CDS_LIB"mstr_standard"
BODY_TYPE"PLUMBING"
HDL_TAP"TRUE";
"B \NAC \NWC"6;
"S \NAC"
BN"8"41;
%"TAP"
"1","(-5950,4525)","2","mstr_standard","I277";
;
CDS_LIB"mstr_standard"
BODY_TYPE"PLUMBING"
HDL_TAP"TRUE";
"B \NAC \NWC"10;
"S \NAC"
BN"4"54;
%"TAP"
"1","(-5950,4425)","2","mstr_standard","I278";
;
CDS_LIB"mstr_standard"
BODY_TYPE"PLUMBING"
HDL_TAP"TRUE";
"B \NAC \NWC"10;
"S \NAC"
BN"5"52;
%"TAP"
"1","(-5950,4325)","2","mstr_standard","I279";
;
CDS_LIB"mstr_standard"
BODY_TYPE"PLUMBING"
HDL_TAP"TRUE";
"B \NAC \NWC"10;
"S \NAC"
BN"6"50;
%"TAP"
"1","(-5950,4225)","2","mstr_standard","I280";
;
CDS_LIB"mstr_standard"
BODY_TYPE"PLUMBING"
HDL_TAP"TRUE";
"B \NAC \NWC"10;
"S \NAC"
BN"7"48;
%"TAP"
"1","(-5950,4125)","2","mstr_standard","I281";
;
CDS_LIB"mstr_standard"
BODY_TYPE"PLUMBING"
HDL_TAP"TRUE";
"B \NAC \NWC"10;
"S \NAC"
BN"8"46;
%"TAP"
"1","(-5750,4075)","2","mstr_standard","I286";
;
CDS_LIB"mstr_standard"
BODY_TYPE"PLUMBING"
HDL_TAP"TRUE";
"B \NAC \NWC"6;
"S \NAC"
BN"9"25;
%"TAP"
"1","(-5950,4025)","2","mstr_standard","I287";
;
CDS_LIB"mstr_standard"
BODY_TYPE"PLUMBING"
HDL_TAP"TRUE";
"B \NAC \NWC"10;
"S \NAC"
BN"9"33;
%"TAP"
"1","(-5950,3825)","2","mstr_standard","I288";
;
CDS_LIB"mstr_standard"
BODY_TYPE"PLUMBING"
HDL_TAP"TRUE";
"B \NAC \NWC"7;
"S \NAC"
BN"1"38;
%"TAP"
"1","(-5950,3875)","2","mstr_standard","I289";
;
CDS_LIB"mstr_standard"
BODY_TYPE"PLUMBING"
HDL_TAP"TRUE";
"B \NAC \NWC"7;
"S \NAC"
BN"0"40;
%"TAP"
"1","(-5950,3775)","2","mstr_standard","I290";
;
CDS_LIB"mstr_standard"
BODY_TYPE"PLUMBING"
HDL_TAP"TRUE";
"B \NAC \NWC"7;
"S \NAC"
BN"2"36;
%"TAP"
"1","(-5950,3725)","2","mstr_standard","I291";
;
CDS_LIB"mstr_standard"
BODY_TYPE"PLUMBING"
HDL_TAP"TRUE";
"B \NAC \NWC"7;
"S \NAC"
BN"3"34;
%"TAP"
"1","(-5950,3675)","2","mstr_standard","I292";
;
CDS_LIB"mstr_standard"
BODY_TYPE"PLUMBING"
HDL_TAP"TRUE";
"B \NAC \NWC"7;
"S \NAC"
BN"4"32;
%"TAP"
"1","(-5950,3625)","2","mstr_standard","I293";
;
CDS_LIB"mstr_standard"
BODY_TYPE"PLUMBING"
HDL_TAP"TRUE";
"B \NAC \NWC"7;
"S \NAC"
BN"5"30;
%"TAP"
"1","(-5950,3575)","2","mstr_standard","I294";
;
CDS_LIB"mstr_standard"
BODY_TYPE"PLUMBING"
HDL_TAP"TRUE";
"B \NAC \NWC"7;
"S \NAC"
BN"6"28;
%"TAP"
"1","(-5950,3425)","2","mstr_standard","I295";
;
CDS_LIB"mstr_standard"
BODY_TYPE"PLUMBING"
HDL_TAP"TRUE";
"B \NAC \NWC"8;
"S \NAC"
BN"1"37;
%"TAP"
"1","(-5950,3475)","2","mstr_standard","I296";
;
CDS_LIB"mstr_standard"
BODY_TYPE"PLUMBING"
HDL_TAP"TRUE";
"B \NAC \NWC"8;
"S \NAC"
BN"0"39;
%"TAP"
"1","(-5950,3325)","2","mstr_standard","I297";
;
CDS_LIB"mstr_standard"
BODY_TYPE"PLUMBING"
HDL_TAP"TRUE";
"B \NAC \NWC"8;
"S \NAC"
BN"3"26;
%"TAP"
"1","(-5950,3375)","2","mstr_standard","I298";
;
CDS_LIB"mstr_standard"
BODY_TYPE"PLUMBING"
HDL_TAP"TRUE";
"B \NAC \NWC"8;
"S \NAC"
BN"2"35;
%"TAP"
"1","(-5950,3275)","2","mstr_standard","I299";
;
CDS_LIB"mstr_standard"
BODY_TYPE"PLUMBING"
HDL_TAP"TRUE";
"B \NAC \NWC"8;
"S \NAC"
BN"4"31;
%"TAP"
"1","(-5950,3225)","2","mstr_standard","I300";
;
CDS_LIB"mstr_standard"
BODY_TYPE"PLUMBING"
HDL_TAP"TRUE";
"B \NAC \NWC"8;
"S \NAC"
BN"5"29;
%"TAP"
"1","(-5950,3175)","2","mstr_standard","I301";
;
CDS_LIB"mstr_standard"
BODY_TYPE"PLUMBING"
HDL_TAP"TRUE";
"B \NAC \NWC"8;
"S \NAC"
BN"6"27;
%"Q_RES"
"1","(-6625,2175)","0","pure_quanta","I314";
;
LOCATION"R503"
$SEC"1"
CDS_SEC"1"
TOLERANCE"1%"
VALUE"15   "
PART_NUMBER"CS01502FB11"
PACK_TYPE"0402LF"
CDS_LIB"pure_quanta"
WATTAGE"1/16W"
MATERIAL"CHIP";
"B"
$PN"2"13;
"A"
$PN"1"11;
END.
